# T6G (Grand Teton) — schematic netlist excerpt (pin names and nets, part order shuffled) for the footprints in the layout excerpt that follows; sources: Cadence DE-HDL packaged netlist, KiCad conversion of 04192023_DAF0TMB3IC0_F0TG_MB_C_brd_V02_OCP.brd

C9103  Q_CAP_DIFFBUS  DIFF BUS_0.22UF 6.3V 20% X6S  pkg C0201  page 67 : \1\ = P3E_CPU1_P4_TX_C_DN<1> ; \2\ = P3E_CPU1_P4_TX_DN<1>
R733  Q_RES  100 1% EMPTY  pkg 0402LF  page 167 : A = P1V8_AUX ; B = FM_JTAG_BMC_R_OE

JP6001  CONN3_210HP1030BR1  CONN3_210-HP1-030BR1 IO  pkg HEADER1X3XG  page 171
  \1\  = PU_U160_EN_N
  \2\  = U160_EN_N
  \3\  = PD_U160_EN_N

(kicad_pcb
	(version 20260206)
	(generator "pcbnew")
	(generator_version "10.0")
	(general
		(thickness 1.6)
		(legacy_teardrops no)
	)
	(paper "A4")
	(title_block
		(title "04192023_DAF0TMB3IC0_F0TG_MB_C_brd_V02_OCP.brd")
		(comment 1 "Grand Teton / footprints 4869-4871 of 8354")
	)
	(layers
		(0 "F.Cu" signal "TOP")
		(4 "In1.Cu" signal "GND")
		(6 "In2.Cu" signal "IN1")
		(8 "In3.Cu" signal "GND1")
		(10 "In4.Cu" signal "IN2")
		(12 "In5.Cu" signal "GND2")
		(14 "In6.Cu" signal "IN3")
		(16 "In7.Cu" signal "GND3")
		(18 "In8.Cu" signal "VCC")
		(20 "In9.Cu" signal "VCC1")
		(22 "In10.Cu" signal "GND4")
		(24 "In11.Cu" signal "IN4")
		(26 "In12.Cu" signal "GND5")
		(28 "In13.Cu" signal "IN5")
		(30 "In14.Cu" signal "GND6")
		(32 "In15.Cu" signal "IN6")
		(34 "In16.Cu" signal "GND7")
		(2 "B.Cu" signal "BOTTOM")
		(9 "F.Adhes" user "F.Adhesive")
		(11 "B.Adhes" user "B.Adhesive")
		(13 "F.Paste" user "Package Geometry/Pastemask Top")
		(15 "B.Paste" user "Package Geometry/Pastemask Bottom")
		(5 "F.SilkS" user "Ref Des/Silkscreen Top")
		(7 "B.SilkS" user "Ref Des/Silkscreen Bottom")
		(1 "F.Mask" user "Board Geometry/Soldermask Top")
		(3 "B.Mask" user "Board Geometry/Soldermask Bottom")
		(17 "Dwgs.User" user "User.Drawings")
		(19 "Cmts.User" user "User.Comments")
		(21 "Eco1.User" user "User.Eco1")
		(23 "Eco2.User" user "User.Eco2")
		(25 "Edge.Cuts" user "Board Geometry/Outline")
		(27 "Margin" user)
		(31 "F.CrtYd" user "Package Geometry/Place Bound Top")
		(29 "B.CrtYd" user "Package Geometry/Place Bound Bottom")
		(35 "F.Fab" user "Ref Des/Assembly Top")
		(33 "B.Fab" user "Ref Des/Assembly Bottom")
	)
	(footprint ""
		(layer "F.Cu")
		(at 180.528468 -48.053498)
		(property "Reference" "C9103"
			(at 0 0 0)
			(layer "F.SilkS")
			(hide yes)
			(effects
				(font
					(size 1.27 1.27)
				)
			)
		)
		(property "Value" ""
			(at 0 0 0)
			(layer "F.Fab")
			(effects
				(font
					(size 1.27 1.27)
				)
			)
		)
		(duplicate_pad_numbers_are_jumpers no)
		(fp_line
			(start -0.299974 -0.150114)
			(end 0.299974 -0.150114)
			(stroke
				(width 0.1)
				(type default)
			)
			(layer "F.Fab")
		)
		(fp_line
			(start -0.299974 0.150114)
			(end -0.299974 -0.150114)
			(stroke
				(width 0.1)
				(type default)
			)
			(layer "F.Fab")
		)
		(fp_line
			(start 0.299974 -0.150114)
			(end 0.299974 0.150114)
			(stroke
				(width 0.1)
				(type default)
			)
			(layer "F.Fab")
		)
		(fp_line
			(start 0.299974 0.150114)
			(end -0.299974 0.150114)
			(stroke
				(width 0.1)
				(type default)
			)
			(layer "F.Fab")
		)
		(pad "1" smd rect
			(at -0.2667 0)
			(size 0.3048 0.381)
			(layers "F.Cu" "F.Mask" "F.Paste")
			(net "P3E_CPU1_P4_TX_C_DN<1>")
		)
		(pad "2" smd rect
			(at 0.2667 0)
			(size 0.3048 0.381)
			(layers "F.Cu" "F.Mask" "F.Paste")
			(net "P3E_CPU1_P4_TX_DN<1>")
		)
	)
	(footprint ""
		(layer "F.Cu")
		(at 25.331166 -78.805024 -90)
		(property "Reference" "JP6001"
			(at -3.135122 6.727444 0)
			(unlocked yes)
			(layer "F.SilkS")
			(effects
				(font
					(size 0.7874 0.5842)
					(thickness 0.1524)
				)
				(justify left)
			)
		)
		(property "Value" ""
			(at 0 0 270)
			(layer "F.Fab")
			(effects
				(font
					(size 1.27 1.27)
				)
			)
		)
		(duplicate_pad_numbers_are_jumpers no)
		(fp_line
			(start -1.249934 6.400038)
			(end -1.249934 -1.320038)
			(stroke
				(width 0.1524)
				(type default)
			)
			(layer "F.SilkS")
		)
		(fp_line
			(start 1.249934 6.400038)
			(end -1.249934 6.400038)
			(stroke
				(width 0.1524)
				(type default)
			)
			(layer "F.SilkS")
		)
		(fp_line
			(start -1.249934 -1.320038)
			(end 1.249934 -1.320038)
			(stroke
				(width 0.1524)
				(type default)
			)
			(layer "F.SilkS")
		)
		(fp_line
			(start 1.249934 -1.320038)
			(end 1.249934 6.400038)
			(stroke
				(width 0.1524)
				(type default)
			)
			(layer "F.SilkS")
		)
		(fp_poly
			(pts
				(xy -2.5654 -0.556514) (xy -1.452372 0) (xy -2.5654 0.556514)
			)
			(stroke
				(width 0)
				(type default)
			)
			(fill yes)
			(layer "F.SilkS")
		)
		(fp_line
			(start -1.249934 6.400038)
			(end -1.249934 -1.320038)
			(stroke
				(width 0.1)
				(type default)
			)
			(layer "F.Fab")
		)
		(fp_line
			(start 1.249934 6.400038)
			(end -1.249934 6.400038)
			(stroke
				(width 0.1)
				(type default)
			)
			(layer "F.Fab")
		)
		(fp_line
			(start -1.249934 -1.320038)
			(end 1.249934 -1.320038)
			(stroke
				(width 0.1)
				(type default)
			)
			(layer "F.Fab")
		)
		(fp_line
			(start 1.249934 -1.320038)
			(end 1.249934 6.400038)
			(stroke
				(width 0.1)
				(type default)
			)
			(layer "F.Fab")
		)
		(fp_poly
			(pts
				(xy -2.5654 -0.556514) (xy -1.452372 0) (xy -2.5654 0.556514)
			)
			(stroke
				(width 0)
				(type default)
			)
			(fill yes)
			(layer "F.Fab")
		)
		(fp_text user "3"
			(at -1.778 5.13207 270)
			(unlocked yes)
			(layer "F.SilkS")
			(effects
				(font
					(size 0.7874 0.5842)
					(thickness 0.1524)
				)
			)
		)
		(fp_text user "3"
			(at -1.1557 5.18287 270)
			(unlocked yes)
			(layer "B.SilkS")
			(effects
				(font
					(size 0.7874 0.5842)
					(thickness 0.1524)
				)
				(justify mirror)
			)
		)
		(fp_text user "1"
			(at -1.143 0.02667 270)
			(unlocked yes)
			(layer "B.SilkS")
			(effects
				(font
					(size 0.7874 0.5842)
					(thickness 0.1524)
				)
				(justify mirror)
			)
		)
		(fp_text user "3"
			(at -1.1557 5.18287 270)
			(unlocked yes)
			(layer "B.Fab")
			(effects
				(font
					(size 0.7874 0.5842)
					(thickness 0.1524)
				)
				(justify mirror)
			)
		)
		(fp_text user "1"
			(at -1.143 0.02667 270)
			(unlocked yes)
			(layer "B.Fab")
			(effects
				(font
					(size 0.7874 0.5842)
					(thickness 0.1524)
				)
				(justify mirror)
			)
		)
		(fp_text user "3"
			(at -1.778 5.13207 270)
			(unlocked yes)
			(layer "F.Fab")
			(effects
				(font
					(size 0.7874 0.5842)
					(thickness 0.1524)
				)
			)
		)
		(pad "1" thru_hole rect
			(at 0 0 270)
			(size 1.5494 1.5494)
			(drill 1.0414)
			(layers "*.Cu" "*.Mask")
			(remove_unused_layers no)
			(net "PU_U160_EN_N")
			(clearance 0)
			(padstack
				(mode front_inner_back)
				(layer "Inner"
					(shape circle)
					(size 1.5494 1.5494)
					(clearance 0)
				)
				(layer "B.Cu"
					(shape rect)
					(size 1.5494 1.5494)
					(clearance 0)
				)
			)
		)
		(pad "2" thru_hole circle
			(at 0 2.54 270)
			(size 1.5494 1.5494)
			(drill 1.0414)
			(layers "*.Cu" "*.Mask")
			(remove_unused_layers no)
			(net "U160_EN_N")
			(clearance 0)
		)
		(pad "3" thru_hole circle
			(at 0 5.08 270)
			(size 1.5494 1.5494)
			(drill 1.0414)
			(layers "*.Cu" "*.Mask")
			(remove_unused_layers no)
			(net "PD_U160_EN_N")
			(clearance 0)
		)
	)
	(footprint ""
		(layer "F.Cu")
		(at 422.129712 -57.447688 -90)
		(property "Reference" "R733"
			(at 0 0 270)
			(layer "F.SilkS")
			(hide yes)
			(effects
				(font
					(size 1.27 1.27)
				)
			)
		)
		(property "Value" ""
			(at 0 0 270)
			(layer "F.Fab")
			(effects
				(font
					(size 1.27 1.27)
				)
			)
		)
		(duplicate_pad_numbers_are_jumpers no)
		(fp_line
			(start -0.7874 0.4064)
			(end -0.7874 -0.4064)
			(stroke
				(width 0.1524)
				(type default)
			)
			(layer "F.SilkS")
		)
		(fp_line
			(start 0.7874 0.4064)
			(end -0.7874 0.4064)
			(stroke
				(width 0.1524)
				(type default)
			)
			(layer "F.SilkS")
		)
		(fp_line
			(start -0.7874 -0.4064)
			(end 0.7874 -0.4064)
			(stroke
				(width 0.1524)
				(type default)
			)
			(layer "F.SilkS")
		)
		(fp_line
			(start 0.7874 -0.4064)
			(end 0.7874 0.4064)
			(stroke
				(width 0.1524)
				(type default)
			)
			(layer "F.SilkS")
		)
		(fp_line
			(start -0.67945 0.3048)
			(end -0.67945 -0.305054)
			(stroke
				(width 0.1)
				(type default)
			)
			(layer "F.Fab")
		)
		(fp_line
			(start -0.12065 0.3048)
			(end -0.67945 0.3048)
			(stroke
				(width 0.1)
				(type default)
			)
			(layer "F.Fab")
		)
		(fp_line
			(start 0.120396 0.3048)
			(end 0.120396 0.2794)
			(stroke
				(width 0.1)
				(type default)
			)
			(layer "F.Fab")
		)
		(fp_line
			(start 0.67945 0.3048)
			(end 0.120396 0.3048)
			(stroke
				(width 0.1)
				(type default)
			)
			(layer "F.Fab")
		)
		(fp_line
			(start -0.12065 0.2794)
			(end -0.12065 0.3048)
			(stroke
				(width 0.1)
				(type default)
			)
			(layer "F.Fab")
		)
		(fp_line
			(start 0.120396 0.2794)
			(end -0.12065 0.2794)
			(stroke
				(width 0.1)
				(type default)
			)
			(layer "F.Fab")
		)
		(fp_line
			(start -0.12065 -0.2794)
			(end 0.12065 -0.2794)
			(stroke
				(width 0.1)
				(type default)
			)
			(layer "F.Fab")
		)
		(fp_line
			(start 0.12065 -0.2794)
			(end 0.12065 -0.3048)
			(stroke
				(width 0.1)
				(type default)
			)
			(layer "F.Fab")
		)
		(fp_line
			(start 0.12065 -0.3048)
			(end 0.67945 -0.3048)
			(stroke
				(width 0.1)
				(type default)
			)
			(layer "F.Fab")
		)
		(fp_line
			(start 0.67945 -0.3048)
			(end 0.67945 0.3048)
			(stroke
				(width 0.1)
				(type default)
			)
			(layer "F.Fab")
		)
		(fp_line
			(start -0.67945 -0.305054)
			(end -0.12065 -0.305054)
			(stroke
				(width 0.1)
				(type default)
			)
			(layer "F.Fab")
		)
		(fp_line
			(start -0.12065 -0.305054)
			(end -0.12065 -0.2794)
			(stroke
				(width 0.1)
				(type default)
			)
			(layer "F.Fab")
		)
		(pad "1" smd circle
			(at -0.40005 0 270)
			(size 0 0)
			(layers "F.Cu" "F.Mask" "F.Paste")
			(net "P1V8_AUX")
		)
		(pad "2" smd circle
			(at 0.40005 0 270)
			(size 0 0)
			(layers "F.Cu" "F.Mask" "F.Paste")
			(net "FM_JTAG_BMC_R_OE")
		)
	)
)
